# S9S_MB_2U (Grand Teton) — schematic netlist excerpt (pin names and nets, part order shuffled) for the footprints in the layout excerpt that follows; sources: Cadence DE-HDL packaged netlist, KiCad conversion of 03242023_DA0F0TMBIJ0_F0T_Motherboard_J_brd_V01_OCP.brd

R4407  Q_RES  33.2 1% CHIP  pkg 0402LF  page 122 : A = H_CPU0_MEMHOT_OUT_VT_N ; B = H_CPU0_MEMHOT_OUT_LVC1_N
PR3798  Q_RES  10 1% CHIP  pkg 0402LF  page 156 : A = P3V3_AUX ; B = P3V3_OCP_VCC_1

(kicad_pcb
	(version 20260206)
	(generator "pcbnew")
	(generator_version "10.0")
	(general
		(thickness 1.6)
		(legacy_teardrops no)
	)
	(paper "A4")
	(title_block
		(title "03242023_DA0F0TMBIJ0_F0T_Motherboard_J_brd_V01_OCP.brd")
		(comment 1 "Grand Teton / footprints 558-559 of 6105")
	)
	(layers
		(0 "F.Cu" signal "TOP")
		(4 "In1.Cu" signal "GND")
		(6 "In2.Cu" signal "IN1")
		(8 "In3.Cu" signal "GND1")
		(10 "In4.Cu" signal "IN2")
		(12 "In5.Cu" signal "GND2")
		(14 "In6.Cu" signal "IN3")
		(16 "In7.Cu" signal "GND3")
		(18 "In8.Cu" signal "VCC")
		(20 "In9.Cu" signal "VCC1")
		(22 "In10.Cu" signal "GND4")
		(24 "In11.Cu" signal "IN4")
		(26 "In12.Cu" signal "GND5")
		(28 "In13.Cu" signal "IN5")
		(30 "In14.Cu" signal "GND6")
		(32 "In15.Cu" signal "IN6")
		(34 "In16.Cu" signal "GND7")
		(2 "B.Cu" signal "BOTTOM")
		(9 "F.Adhes" user "F.Adhesive")
		(11 "B.Adhes" user "B.Adhesive")
		(13 "F.Paste" user "Package Geometry/Pastemask Top")
		(15 "B.Paste" user "Package Geometry/Pastemask Bottom")
		(5 "F.SilkS" user "Ref Des/Silkscreen Top")
		(7 "B.SilkS" user "Ref Des/Silkscreen Bottom")
		(1 "F.Mask" user "Board Geometry/Soldermask Top")
		(3 "B.Mask" user "Board Geometry/Soldermask Bottom")
		(17 "Dwgs.User" user "User.Drawings")
		(19 "Cmts.User" user "User.Comments")
		(21 "Eco1.User" user "User.Eco1")
		(23 "Eco2.User" user "User.Eco2")
		(25 "Edge.Cuts" user "Board Geometry/Outline")
		(27 "Margin" user)
		(31 "F.CrtYd" user "Package Geometry/Place Bound Top")
		(29 "B.CrtYd" user "Package Geometry/Place Bound Bottom")
		(35 "F.Fab" user "Ref Des/Assembly Top")
		(33 "B.Fab" user "Ref Des/Assembly Bottom")
	)
	(footprint ""
		(layer "F.Cu")
		(at 435.997858 -106.76636 180)
		(property "Reference" "PR3798"
			(at 0 0 180)
			(layer "F.SilkS")
			(hide yes)
			(effects
				(font
					(size 1.27 1.27)
				)
			)
		)
		(property "Value" ""
			(at 0 0 180)
			(layer "F.Fab")
			(effects
				(font
					(size 1.27 1.27)
				)
			)
		)
		(duplicate_pad_numbers_are_jumpers no)
		(fp_line
			(start 0.7874 0.4064)
			(end -0.7874 0.4064)
			(stroke
				(width 0.1524)
				(type default)
			)
			(layer "F.SilkS")
		)
		(fp_line
			(start 0.7874 -0.4064)
			(end 0.7874 0.4064)
			(stroke
				(width 0.1524)
				(type default)
			)
			(layer "F.SilkS")
		)
		(fp_line
			(start -0.7874 0.4064)
			(end -0.7874 -0.4064)
			(stroke
				(width 0.1524)
				(type default)
			)
			(layer "F.SilkS")
		)
		(fp_line
			(start -0.7874 -0.4064)
			(end 0.7874 -0.4064)
			(stroke
				(width 0.1524)
				(type default)
			)
			(layer "F.SilkS")
		)
		(fp_line
			(start 0.67945 0.3048)
			(end 0.120396 0.3048)
			(stroke
				(width 0.1)
				(type default)
			)
			(layer "F.Fab")
		)
		(fp_line
			(start 0.67945 -0.3048)
			(end 0.67945 0.3048)
			(stroke
				(width 0.1)
				(type default)
			)
			(layer "F.Fab")
		)
		(fp_line
			(start 0.12065 -0.2794)
			(end 0.12065 -0.3048)
			(stroke
				(width 0.1)
				(type default)
			)
			(layer "F.Fab")
		)
		(fp_line
			(start 0.12065 -0.3048)
			(end 0.67945 -0.3048)
			(stroke
				(width 0.1)
				(type default)
			)
			(layer "F.Fab")
		)
		(fp_line
			(start 0.120396 0.3048)
			(end 0.120396 0.2794)
			(stroke
				(width 0.1)
				(type default)
			)
			(layer "F.Fab")
		)
		(fp_line
			(start 0.120396 0.2794)
			(end -0.12065 0.2794)
			(stroke
				(width 0.1)
				(type default)
			)
			(layer "F.Fab")
		)
		(fp_line
			(start -0.12065 0.3048)
			(end -0.67945 0.3048)
			(stroke
				(width 0.1)
				(type default)
			)
			(layer "F.Fab")
		)
		(fp_line
			(start -0.12065 0.2794)
			(end -0.12065 0.3048)
			(stroke
				(width 0.1)
				(type default)
			)
			(layer "F.Fab")
		)
		(fp_line
			(start -0.12065 -0.2794)
			(end 0.12065 -0.2794)
			(stroke
				(width 0.1)
				(type default)
			)
			(layer "F.Fab")
		)
		(fp_line
			(start -0.12065 -0.305054)
			(end -0.12065 -0.2794)
			(stroke
				(width 0.1)
				(type default)
			)
			(layer "F.Fab")
		)
		(fp_line
			(start -0.67945 0.3048)
			(end -0.67945 -0.305054)
			(stroke
				(width 0.1)
				(type default)
			)
			(layer "F.Fab")
		)
		(fp_line
			(start -0.67945 -0.305054)
			(end -0.12065 -0.305054)
			(stroke
				(width 0.1)
				(type default)
			)
			(layer "F.Fab")
		)
		(pad "1" smd circle
			(at -0.40005 0 180)
			(size 0 0)
			(layers "F.Cu" "F.Mask" "F.Paste")
			(net "P3V3_AUX")
		)
		(pad "2" smd circle
			(at 0.40005 0 180)
			(size 0 0)
			(layers "F.Cu" "F.Mask" "F.Paste")
			(net "P3V3_OCP_VCC_1")
		)
	)
	(footprint ""
		(layer "F.Cu")
		(at 131.75488 -92.674948 -90)
		(property "Reference" "R4407"
			(at 0 0 270)
			(layer "F.SilkS")
			(hide yes)
			(effects
				(font
					(size 1.27 1.27)
				)
			)
		)
		(property "Value" ""
			(at 0 0 270)
			(layer "F.Fab")
			(effects
				(font
					(size 1.27 1.27)
				)
			)
		)
		(duplicate_pad_numbers_are_jumpers no)
		(fp_line
			(start -0.7874 0.4064)
			(end -0.7874 -0.4064)
			(stroke
				(width 0.1524)
				(type default)
			)
			(layer "F.SilkS")
		)
		(fp_line
			(start 0.7874 0.4064)
			(end -0.7874 0.4064)
			(stroke
				(width 0.1524)
				(type default)
			)
			(layer "F.SilkS")
		)
		(fp_line
			(start -0.7874 -0.4064)
			(end 0.7874 -0.4064)
			(stroke
				(width 0.1524)
				(type default)
			)
			(layer "F.SilkS")
		)
		(fp_line
			(start 0.7874 -0.4064)
			(end 0.7874 0.4064)
			(stroke
				(width 0.1524)
				(type default)
			)
			(layer "F.SilkS")
		)
		(fp_line
			(start -0.67945 0.3048)
			(end -0.67945 -0.305054)
			(stroke
				(width 0.1)
				(type default)
			)
			(layer "F.Fab")
		)
		(fp_line
			(start -0.12065 0.3048)
			(end -0.67945 0.3048)
			(stroke
				(width 0.1)
				(type default)
			)
			(layer "F.Fab")
		)
		(fp_line
			(start 0.120396 0.3048)
			(end 0.120396 0.2794)
			(stroke
				(width 0.1)
				(type default)
			)
			(layer "F.Fab")
		)
		(fp_line
			(start 0.67945 0.3048)
			(end 0.120396 0.3048)
			(stroke
				(width 0.1)
				(type default)
			)
			(layer "F.Fab")
		)
		(fp_line
			(start -0.12065 0.2794)
			(end -0.12065 0.3048)
			(stroke
				(width 0.1)
				(type default)
			)
			(layer "F.Fab")
		)
		(fp_line
			(start 0.120396 0.2794)
			(end -0.12065 0.2794)
			(stroke
				(width 0.1)
				(type default)
			)
			(layer "F.Fab")
		)
		(fp_line
			(start -0.12065 -0.2794)
			(end 0.12065 -0.2794)
			(stroke
				(width 0.1)
				(type default)
			)
			(layer "F.Fab")
		)
		(fp_line
			(start 0.12065 -0.2794)
			(end 0.12065 -0.3048)
			(stroke
				(width 0.1)
				(type default)
			)
			(layer "F.Fab")
		)
		(fp_line
			(start 0.12065 -0.3048)
			(end 0.67945 -0.3048)
			(stroke
				(width 0.1)
				(type default)
			)
			(layer "F.Fab")
		)
		(fp_line
			(start 0.67945 -0.3048)
			(end 0.67945 0.3048)
			(stroke
				(width 0.1)
				(type default)
			)
			(layer "F.Fab")
		)
		(fp_line
			(start -0.67945 -0.305054)
			(end -0.12065 -0.305054)
			(stroke
				(width 0.1)
				(type default)
			)
			(layer "F.Fab")
		)
		(fp_line
			(start -0.12065 -0.305054)
			(end -0.12065 -0.2794)
			(stroke
				(width 0.1)
				(type default)
			)
			(layer "F.Fab")
		)
		(pad "1" smd circle
			(at -0.40005 0 270)
			(size 0 0)
			(layers "F.Cu" "F.Mask" "F.Paste")
			(net "H_CPU0_MEMHOT_OUT_VT_N")
		)
		(pad "2" smd circle
			(at 0.40005 0 270)
			(size 0 0)
			(layers "F.Cu" "F.Mask" "F.Paste")
			(net "H_CPU0_MEMHOT_OUT_LVC1_N")
		)
	)
)
